FILE_TYPE = MACRO_DRAWING;
SET COLOR_WIRE YELLOW;
SET COLOR_PROP ORANGE;
SET COLOR_DOT WHITE;
SET COLOR_ARC YELLOW;
SET COLOR_BODY GREEN;
SET COLOR_NOTE PURPLE;
SET PROP_DISPLAY VALUE;
SET PAGE_NUMBER P154;
FORCEADD QUANTA_TITLE_BLOCK_C..1
(0 0);
FORCEPROP 1 LAST CUSTOM_TXT_CDS <NAME_2>
J 0
(-3175 50);
FORCEPROP 1 LAST CUSTOM_TXT_CDS <NAME_1>
J 0
(-3175 175);
FORCEPROP 1 LAST CUSTOM_TXT_CDS <Q_NUMBER>
J 0
(-1403 103);
DISPLAY 1.212766 (-1403 103);
FORCEPROP 1 LAST CUSTOM_TXT_CDS <Q_PROJ>
J 0
(-2382 102);
DISPLAY 1.212766 (-2382 102);
FORCEPROP 1 LAST CUSTOM_TXT_CDS <Q_REV>
J 0
(-184 103);
DISPLAY 1.212766 (-184 103);
FORCEPROP 1 LAST CUSTOM_TXT_CDS <CON_LAST_MODIFIED>
J 0
(-1885 15);
DISPLAY 0.978723 (-1885 15);
FORCEPROP 1 LAST CUSTOM_TXT_CDS <CON_PAGE_NUM> OF <CON_TOTAL_PAGES>
J 0
(-446 18);
DISPLAY 0.978723 (-446 18);
FORCEPROP 1 LAST Q_DEPT BU9
J 1
(-3763 49);
DISPLAY 1.957447 (-3763 49);
PAINT GREEN (-3763 49);
FORCEPROP 1 LAST Q_TITLE FAN - DUAL ROTOR (1/2)
J 0
(-9275 75);
DISPLAY 2.446809 (-9275 75);
PAINT GREEN (-9275 75);
FORCEPROP 2 LAST PAGE_BORDER TRUE
J 0
(-7890 5250);
DISPLAY 0.638298 (-7890 5250);
PAINT PINK (-7890 5250);
DISPLAY INVISIBLE (-7890 5250);
FORCEPROP 2 LAST CDS_LIB pure_quanta
J 0
(0 0);
DISPLAY INVISIBLE (0 0);
FORCEPROP 1 LAST CDS_LMAN_SYM_OUTLINE -9475,6775,100,-125
J 0
(0 0);
DISPLAY 0.468085 (0 0);
PAINT GREEN (0 0);
DISPLAY INVISIBLE (0 0);
FORCEPROP 1 LAST COMMENT_BODY TRUE
J 0
(12 -13);
DISPLAY 0.978723 (12 -13);
PAINT GREEN (12 -13);
DISPLAY INVISIBLE (12 -13);
FORCEPROP 2 LAST CDS_XR_PAGE_TITLE CR-154 : @T6G_MB_LIB.T6G(SCH_1):PAGE154
J 0
(-7890 5250);
DISPLAY 0.638298 (-7890 5250);
PAINT PINK (-7890 5250);
DISPLAY INVISIBLE (-7890 5250);
FORCEPROP 2 LAST CUSTOM_TXT_CDS <XR_PAGE_TITLE>
J 0
(-7890 5250);
DISPLAY 0.638298 (-7890 5250);
PAINT PINK (-7890 5250);
DISPLAY INVISIBLE (-7890 5250);
FORCEPROP 0 LAST CDS_CON_LAST_MODIFIED Wed Mar 09 20:27:28 2022
J 0
(-1885 15);
DISPLAY INVISIBLE (-1885 15);
QUIT
